(kicad_pcb
	(version 20240108)
	(generator "pcbnew")
	(generator_version "8.0")
	(general
		(thickness 1.62)
		(legacy_teardrops no)
	)
	(paper "A4")
	(title_block
		(title "Jetson Orin Baseboard")
		(date "2025-03-12")
		(rev "1.3.4")
		(company "Antmicro Ltd")
		(comment 1 "www.antmicro.com")
		(comment 9 "footprints 418-422 of 677")
	)
	(layers
		(0 "F.Cu" signal)
		(1 "In1.Cu" signal)
		(2 "In2.Cu" signal)
		(3 "In3.Cu" signal)
		(4 "In4.Cu" jumper)
		(5 "In5.Cu" signal)
		(6 "In6.Cu" signal)
		(31 "B.Cu" signal)
		(32 "B.Adhes" user "B.Adhesive")
		(33 "F.Adhes" user "F.Adhesive")
		(34 "B.Paste" user)
		(35 "F.Paste" user)
		(36 "B.SilkS" user "B.Silkscreen")
		(37 "F.SilkS" user "F.Silkscreen")
		(38 "B.Mask" user)
		(39 "F.Mask" user)
		(40 "Dwgs.User" user "User.Drawings")
		(41 "Cmts.User" user "User.Comments")
		(42 "Eco1.User" user "User.Eco1")
		(43 "Eco2.User" user "User.Eco2")
		(44 "Edge.Cuts" user)
		(45 "Margin" user)
		(46 "B.CrtYd" user "B.Courtyard")
		(47 "F.CrtYd" user "F.Courtyard")
		(48 "B.Fab" user)
		(49 "F.Fab" user)
	)
	(footprint "antmicro-footprints:Mech_M2_2280_H2.5mm"
		(layer "B.Cu")
		(at 40.74 86.7795 -90)
		(property "Reference" "M3"
			(at 4.4205 0.74 0)
			(layer "B.SilkS")
			(effects
				(font
					(size 0.7 0.7)
					(thickness 0.15)
				)
				(justify left top mirror)
			)
		)
		(property "Value" "Mech_M2_2280_H2.5mm"
			(at 0 -6.857 90)
			(layer "B.Fab")
			(effects
				(font
					(size 0.7 0.7)
					(thickness 0.15)
				)
				(justify right bottom mirror)
			)
		)
		(property "Footprint" "antmicro-footprints:Mech_M2_2280_H2.5mm"
			(at 0 0 90)
			(layer "B.Fab")
			(hide yes)
			(effects
				(font
					(size 1.27 1.27)
					(thickness 0.15)
				)
			)
		)
		(property "Manufacturer" ""
			(at 0 0 -90)
			(unlocked yes)
			(layer "B.Fab")
			(hide yes)
			(effects
				(font
					(size 1 1)
					(thickness 0.15)
				)
				(justify mirror)
			)
		)
		(property "MPN" ""
			(at 0 0 -90)
			(unlocked yes)
			(layer "B.Fab")
			(hide yes)
			(effects
				(font
					(size 1 1)
					(thickness 0.15)
				)
				(justify mirror)
			)
		)
		(property "Author" "Antmicro"
			(at 0 0 -90)
			(unlocked yes)
			(layer "B.Fab")
			(hide yes)
			(effects
				(font
					(size 1 1)
					(thickness 0.15)
				)
				(justify mirror)
			)
		)
		(property "License" "Apache-2.0"
			(at 0 0 -90)
			(unlocked yes)
			(layer "B.Fab")
			(hide yes)
			(effects
				(font
					(size 1 1)
					(thickness 0.15)
				)
				(justify mirror)
			)
		)
		(sheetname "M.2")
		(sheetfile "m-2.kicad_sch")
		(attr exclude_from_pos_files exclude_from_bom allow_missing_courtyard dnp)
		(fp_rect
			(start -10.922 -0.0508)
			(end 11.0236 -80.0608)
			(stroke
				(width 0.15)
				(type solid)
			)
			(fill none)
			(layer "B.Fab")
		)
		(fp_text user "License: Apache-2.0"
			(at -12.2428 -84.3922 90)
			(layer "B.Fab")
			(hide yes)
			(effects
				(font
					(size 0.7 0.7)
					(thickness 0.15)
				)
				(justify left bottom mirror)
			)
		)
		(fp_text user "Author: Antmicro"
			(at -12.2428 -83.1912 90)
			(layer "B.Fab")
			(hide yes)
			(effects
				(font
					(size 0.7 0.7)
					(thickness 0.15)
				)
				(justify left bottom mirror)
			)
		)
		(fp_text user "${REFERENCE}"
			(at -12.2428 -81.9912 90)
			(layer "B.Fab")
			(hide yes)
			(effects
				(font
					(size 0.7 0.7)
					(thickness 0.15)
				)
				(justify left bottom mirror)
			)
		)
	)
	(footprint "antmicro-footprints:SOD-523"
		(layer "B.Cu")
		(at 55.25 80.75 90)
		(property "Reference" "D34"
			(at -0.25 1.375 -90)
			(layer "B.SilkS")
			(effects
				(font
					(size 0.7 0.7)
					(thickness 0.15)
				)
				(justify left bottom mirror)
			)
		)
		(property "Value" "RB521S30T1G"
			(at 0 -1.499 -90)
			(layer "B.Fab")
			(effects
				(font
					(size 0.7 0.7)
					(thickness 0.15)
				)
				(justify left bottom mirror)
			)
		)
		(property "Footprint" "antmicro-footprints:SOD-523"
			(at 0 0 90)
			(layer "F.Fab")
			(hide yes)
			(effects
				(font
					(size 1.27 1.27)
					(thickness 0.15)
				)
			)
		)
		(property "Datasheet" "https://www.onsemi.com/pdf/datasheet/rb521s30t1-d.pdf"
			(at 0 0 90)
			(layer "F.Fab")
			(hide yes)
			(effects
				(font
					(size 1.27 1.27)
					(thickness 0.15)
				)
			)
		)
		(property "Author" "Antmicro"
			(at 135.65 26.15 0)
			(layer "B.Fab")
			(hide yes)
			(effects
				(font
					(size 1 1)
					(thickness 0.15)
				)
				(justify mirror)
			)
		)
		(property "License" "Apache-2.0"
			(at 135.65 26.15 0)
			(layer "B.Fab")
			(hide yes)
			(effects
				(font
					(size 1 1)
					(thickness 0.15)
				)
				(justify mirror)
			)
		)
		(property "MPN" "RB521S30T1G"
			(at 135.65 26.15 0)
			(layer "B.Fab")
			(hide yes)
			(effects
				(font
					(size 1 1)
					(thickness 0.15)
				)
				(justify mirror)
			)
		)
		(property "Manufacturer" "ON Semiconductor"
			(at 135.65 26.15 0)
			(layer "B.Fab")
			(hide yes)
			(effects
				(font
					(size 1 1)
					(thickness 0.15)
				)
				(justify mirror)
			)
		)
		(sheetname "SoM")
		(sheetfile "som.kicad_sch")
		(attr smd)
		(fp_line
			(start -0.35 -0.5)
			(end -0.35 0.5)
			(stroke
				(width 0.15)
				(type solid)
			)
			(layer "B.SilkS")
		)
		(fp_rect
			(start -1 0.6)
			(end 1 -0.6)
			(stroke
				(width 0.05)
				(type solid)
			)
			(fill none)
			(layer "B.CrtYd")
		)
		(fp_line
			(start 0.65 -0.423)
			(end -0.652 -0.423)
			(stroke
				(width 0.15)
				(type solid)
			)
			(layer "B.Fab")
		)
		(fp_line
			(start 0.65 -0.423)
			(end 0.65 0.425)
			(stroke
				(width 0.15)
				(type solid)
			)
			(layer "B.Fab")
		)
		(fp_line
			(start -0.35 -0.4)
			(end -0.35 0.4)
			(stroke
				(width 0.15)
				(type solid)
			)
			(layer "B.Fab")
		)
		(fp_line
			(start 0.65 0.425)
			(end -0.652 0.425)
			(stroke
				(width 0.15)
				(type solid)
			)
			(layer "B.Fab")
		)
		(fp_line
			(start -0.652 0.425)
			(end -0.652 -0.423)
			(stroke
				(width 0.15)
				(type solid)
			)
			(layer "B.Fab")
		)
		(fp_text user "Author: Antmicro"
			(at -1.276 -4.7 -90)
			(layer "B.Fab")
			(hide yes)
			(effects
				(font
					(size 0.7 0.7)
					(thickness 0.15)
				)
				(justify left bottom mirror)
			)
		)
		(fp_text user "License: Apache-2.0"
			(at -1.276 -5.9 -90)
			(layer "B.Fab")
			(hide yes)
			(effects
				(font
					(size 0.7 0.7)
					(thickness 0.15)
				)
				(justify left bottom mirror)
			)
		)
		(fp_text user "${REFERENCE}"
			(at -1.276 -3.499 -90)
			(layer "B.Fab")
			(hide yes)
			(effects
				(font
					(size 0.7 0.7)
					(thickness 0.15)
				)
				(justify left bottom mirror)
			)
		)
		(pad "1" smd roundrect
			(at -0.701 0 90)
			(size 0.5 0.6)
			(layers "B.Cu" "B.Paste" "B.Mask")
			(roundrect_rratio 0.25)
			(net 85 "/SoM/PMIC_BBAT")
			(pinfunction "C")
			(pintype "passive")
		)
		(pad "2" smd roundrect
			(at 0.699 0 90)
			(size 0.5 0.6)
			(layers "B.Cu" "B.Paste" "B.Mask")
			(roundrect_rratio 0.25)
			(net 117 "3V3_STDB")
			(pinfunction "A")
			(pintype "passive")
		)
	)
	(footprint "antmicro-footprints:R_0402_1005Metric"
		(layer "B.Cu")
		(at 108.1 112 -90)
		(descr "Resistor SMD 0402")
		(tags "resistor SMD 0402")
		(property "Reference" "R24"
			(at 0.75 -0.4 90)
			(layer "B.SilkS")
			(effects
				(font
					(size 0.7 0.7)
					(thickness 0.15)
				)
				(justify left bottom mirror)
			)
		)
		(property "Value" "R_10k_0402"
			(at 0 -1.4 90)
			(layer "B.Fab")
			(effects
				(font
					(size 0.7 0.7)
					(thickness 0.15)
				)
				(justify left bottom mirror)
			)
		)
		(property "Footprint" "antmicro-footprints:R_0402_1005Metric"
			(at 0 0 -90)
			(layer "F.Fab")
			(hide yes)
			(effects
				(font
					(size 1.27 1.27)
					(thickness 0.15)
				)
			)
		)
		(property "Datasheet" "https://www.bourns.com/docs/product-datasheets/cr.pdf"
			(at 0 0 -90)
			(layer "F.Fab")
			(hide yes)
			(effects
				(font
					(size 1.27 1.27)
					(thickness 0.15)
				)
			)
		)
		(property "Author" "Antmicro"
			(at -3.9 220.1 0)
			(layer "B.Fab")
			(hide yes)
			(effects
				(font
					(size 1 1)
					(thickness 0.15)
				)
				(justify mirror)
			)
		)
		(property "License" "Apache-2.0"
			(at -3.9 220.1 0)
			(layer "B.Fab")
			(hide yes)
			(effects
				(font
					(size 1 1)
					(thickness 0.15)
				)
				(justify mirror)
			)
		)
		(property "MPN" "CR0402-FX-1002GLF"
			(at -3.9 220.1 0)
			(layer "B.Fab")
			(hide yes)
			(effects
				(font
					(size 1 1)
					(thickness 0.15)
				)
				(justify mirror)
			)
		)
		(property "Manufacturer" "Bourns"
			(at -3.9 220.1 0)
			(layer "B.Fab")
			(hide yes)
			(effects
				(font
					(size 1 1)
					(thickness 0.15)
				)
				(justify mirror)
			)
		)
		(property "Tolerance" "1%"
			(at -3.9 220.1 0)
			(layer "B.Fab")
			(hide yes)
			(effects
				(font
					(size 1 1)
					(thickness 0.15)
				)
				(justify mirror)
			)
		)
		(property "Val" "10k"
			(at -3.9 220.1 0)
			(layer "B.Fab")
			(hide yes)
			(effects
				(font
					(size 1 1)
					(thickness 0.15)
				)
				(justify mirror)
			)
		)
		(sheetname "USB3")
		(sheetfile "usb3.kicad_sch")
		(attr smd)
		(fp_rect
			(start -0.925 0.47)
			(end 0.925 -0.47)
			(stroke
				(width 0.05)
				(type default)
			)
			(fill none)
			(layer "B.CrtYd")
		)
		(fp_rect
			(start -0.5 0.25)
			(end 0.5 -0.25)
			(stroke
				(width 0.15)
				(type solid)
			)
			(fill none)
			(layer "B.Fab")
		)
		(fp_text user "${REFERENCE}"
			(at -0.95 -3.168 90)
			(layer "B.Fab")
			(hide yes)
			(effects
				(font
					(size 0.7 0.7)
					(thickness 0.15)
				)
				(justify left bottom mirror)
			)
		)
		(fp_text user "Author: Antmicro"
			(at -0.95 -4.169 90)
			(layer "B.Fab")
			(hide yes)
			(effects
				(font
					(size 0.7 0.7)
					(thickness 0.15)
				)
				(justify left bottom mirror)
			)
		)
		(fp_text user "License: Apache-2.0"
			(at -0.95 -5.169 90)
			(layer "B.Fab")
			(hide yes)
			(effects
				(font
					(size 0.7 0.7)
					(thickness 0.15)
				)
				(justify left bottom mirror)
			)
		)
		(pad "1" smd roundrect
			(at -0.48 0 270)
			(size 0.59 0.64)
			(layers "B.Cu" "B.Paste" "B.Mask")
			(roundrect_rratio 0.25)
			(net 632 "Net-(Q19-G)")
			(pintype "passive")
		)
		(pad "2" smd roundrect
			(at 0.48 0 270)
			(size 0.59 0.64)
			(layers "B.Cu" "B.Paste" "B.Mask")
			(roundrect_rratio 0.25)
			(net 284 "/USB3/USBC1_ID")
			(pintype "passive")
		)
	)
	(footprint "antmicro-footprints:R_0402_1005Metric"
		(layer "B.Cu")
		(at 51.02 83.92 180)
		(descr "Resistor SMD 0402")
		(tags "resistor SMD 0402")
		(property "Reference" "R148"
			(at 0.82 -0.53 180)
			(layer "B.SilkS")
			(effects
				(font
					(size 0.7 0.7)
					(thickness 0.15)
				)
				(justify left bottom mirror)
			)
		)
		(property "Value" "R_10k_0402"
			(at 0 -1.4 0)
			(layer "B.Fab")
			(effects
				(font
					(size 0.7 0.7)
					(thickness 0.15)
				)
				(justify left bottom mirror)
			)
		)
		(property "Footprint" "antmicro-footprints:R_0402_1005Metric"
			(at 0 0 180)
			(layer "F.Fab")
			(hide yes)
			(effects
				(font
					(size 1.27 1.27)
					(thickness 0.15)
				)
			)
		)
		(property "Datasheet" "https://www.bourns.com/docs/product-datasheets/cr.pdf"
			(at 0 0 180)
			(layer "F.Fab")
			(hide yes)
			(effects
				(font
					(size 1.27 1.27)
					(thickness 0.15)
				)
			)
		)
		(property "Author" "Antmicro"
			(at 103.8 167.475 0)
			(layer "B.Fab")
			(hide yes)
			(effects
				(font
					(size 1 1)
					(thickness 0.15)
				)
				(justify mirror)
			)
		)
		(property "License" "Apache-2.0"
			(at 103.8 167.475 0)
			(layer "B.Fab")
			(hide yes)
			(effects
				(font
					(size 1 1)
					(thickness 0.15)
				)
				(justify mirror)
			)
		)
		(property "MPN" "CR0402-FX-1002GLF"
			(at 103.8 167.475 0)
			(layer "B.Fab")
			(hide yes)
			(effects
				(font
					(size 1 1)
					(thickness 0.15)
				)
				(justify mirror)
			)
		)
		(property "Manufacturer" "Bourns"
			(at 103.8 167.475 0)
			(layer "B.Fab")
			(hide yes)
			(effects
				(font
					(size 1 1)
					(thickness 0.15)
				)
				(justify mirror)
			)
		)
		(property "Tolerance" "1%"
			(at 103.8 167.475 0)
			(layer "B.Fab")
			(hide yes)
			(effects
				(font
					(size 1 1)
					(thickness 0.15)
				)
				(justify mirror)
			)
		)
		(property "Val" "10k"
			(at 103.8 167.475 0)
			(layer "B.Fab")
			(hide yes)
			(effects
				(font
					(size 1 1)
					(thickness 0.15)
				)
				(justify mirror)
			)
		)
		(sheetname "Ethernet")
		(sheetfile "ethernet.kicad_sch")
		(attr smd)
		(fp_rect
			(start -0.925 0.47)
			(end 0.925 -0.47)
			(stroke
				(width 0.05)
				(type default)
			)
			(fill none)
			(layer "B.CrtYd")
		)
		(fp_rect
			(start -0.5 0.25)
			(end 0.5 -0.25)
			(stroke
				(width 0.15)
				(type solid)
			)
			(fill none)
			(layer "B.Fab")
		)
		(fp_text user "Author: Antmicro"
			(at -0.95 -4.169 0)
			(layer "B.Fab")
			(hide yes)
			(effects
				(font
					(size 0.7 0.7)
					(thickness 0.15)
				)
				(justify left bottom mirror)
			)
		)
		(fp_text user "License: Apache-2.0"
			(at -0.95 -5.169 0)
			(layer "B.Fab")
			(hide yes)
			(effects
				(font
					(size 0.7 0.7)
					(thickness 0.15)
				)
				(justify left bottom mirror)
			)
		)
		(fp_text user "${REFERENCE}"
			(at -0.95 -3.168 0)
			(layer "B.Fab")
			(hide yes)
			(effects
				(font
					(size 0.7 0.7)
					(thickness 0.15)
				)
				(justify left bottom mirror)
			)
		)
		(pad "1" smd roundrect
			(at -0.48 0 180)
			(size 0.59 0.64)
			(layers "B.Cu" "B.Paste" "B.Mask")
			(roundrect_rratio 0.25)
			(net 127 "/Ethernet/POE_ACTIVE")
			(pintype "passive")
		)
		(pad "2" smd roundrect
			(at 0.48 0 180)
			(size 0.59 0.64)
			(layers "B.Cu" "B.Paste" "B.Mask")
			(roundrect_rratio 0.25)
			(net 571 "/Ethernet/PG")
			(pintype "passive")
		)
	)
	(footprint "antmicro-footprints:SOT-23-6"
		(layer "B.Cu")
		(at 68.5 75.25 -90)
		(property "Reference" "U38"
			(at 2.09 -15.76 90)
			(layer "B.SilkS")
			(effects
				(font
					(size 0.7 0.7)
					(thickness 0.15)
				)
				(justify left bottom mirror)
			)
		)
		(property "Value" "74LVC1G175_SOT457"
			(at -1.75 -2.75 90)
			(layer "B.Fab")
			(effects
				(font
					(size 0.7 0.7)
					(thickness 0.15)
				)
				(justify left bottom mirror)
			)
		)
		(property "Footprint" "antmicro-footprints:SOT-23-6"
			(at 0 0 90)
			(layer "B.Fab")
			(hide yes)
			(effects
				(font
					(size 1.27 1.27)
					(thickness 0.15)
				)
			)
		)
		(property "Datasheet" "https://www.mouser.com/datasheet/2/916/74LVC1G175-1480578.pdf"
			(at 0 0 90)
			(layer "B.Fab")
			(hide yes)
			(effects
				(font
					(size 1.27 1.27)
					(thickness 0.15)
				)
			)
		)
		(property "MPN" "74LVC1G175GV,125"
			(at 0 0 -90)
			(unlocked yes)
			(layer "B.Fab")
			(hide yes)
			(effects
				(font
					(size 1 1)
					(thickness 0.15)
				)
				(justify mirror)
			)
		)
		(property "Manufacturer" "Nexperia"
			(at 0 0 -90)
			(unlocked yes)
			(layer "B.Fab")
			(hide yes)
			(effects
				(font
					(size 1 1)
					(thickness 0.15)
				)
				(justify mirror)
			)
		)
		(property "Author" "Antmicro"
			(at 0 0 -90)
			(unlocked yes)
			(layer "B.Fab")
			(hide yes)
			(effects
				(font
					(size 1 1)
					(thickness 0.15)
				)
				(justify mirror)
			)
		)
		(property "License" "Apache-2.0"
			(at 0 0 -90)
			(unlocked yes)
			(layer "B.Fab")
			(hide yes)
			(effects
				(font
					(size 1 1)
					(thickness 0.15)
				)
				(justify mirror)
			)
		)
		(sheetname "Supply")
		(sheetfile "supply.kicad_sch")
		(attr smd)
		(fp_line
			(start -1.45 0.757)
			(end -1.3 0.757)
			(stroke
				(width 0.12)
				(type solid)
			)
			(layer "B.SilkS")
		)
		(fp_line
			(start 1.45 0.757)
			(end 1.3 0.757)
			(stroke
				(width 0.12)
				(type solid)
			)
			(layer "B.SilkS")
		)
		(fp_line
			(start -1.45 0.457)
			(end -1.45 0.757)
			(stroke
				(width 0.12)
				(type solid)
			)
			(layer "B.SilkS")
		)
		(fp_line
			(start 1.45 0.457)
			(end 1.45 0.757)
			(stroke
				(width 0.12)
				(type solid)
			)
			(layer "B.SilkS")
		)
		(fp_line
			(start -1.45 -0.343)
			(end -1.45 -0.643)
			(stroke
				(width 0.12)
				(type solid)
			)
			(layer "B.SilkS")
		)
		(fp_line
			(start 1.45 -0.343)
			(end 1.45 -0.643)
			(stroke
				(width 0.12)
				(type solid)
			)
			(layer "B.SilkS")
		)
		(fp_line
			(start 1.45 -0.643)
			(end 1.3 -0.643)
			(stroke
				(width 0.12)
				(type solid)
			)
			(layer "B.SilkS")
		)
		(fp_rect
			(start -1.55 1.85)
			(end 1.55 -1.75)
			(stroke
				(width 0.05)
				(type solid)
			)
			(fill none)
			(layer "B.CrtYd")
		)
		(fp_line
			(start -1.5 0.757)
			(end -1.5 -0.643)
			(stroke
				(width 0.1)
				(type solid)
			)
			(layer "B.Fab")
		)
		(fp_line
			(start 1.5 0.757)
			(end -1.5 0.757)
			(stroke
				(width 0.1)
				(type solid)
			)
			(layer "B.Fab")
		)
		(fp_line
			(start -1.5 -0.643)
			(end 1.5 -0.643)
			(stroke
				(width 0.1)
				(type solid)
			)
			(layer "B.Fab")
		)
		(fp_line
			(start 1.5 -0.643)
			(end 1.5 0.757)
			(stroke
				(width 0.1)
				(type solid)
			)
			(layer "B.Fab")
		)
		(fp_text user "."
			(at -1.4 -1.2 90)
			(layer "B.SilkS")
			(effects
				(font
					(size 1 1)
					(thickness 0.15)
				)
				(justify mirror)
			)
		)
		(fp_text user "${REFERENCE}"
			(at -1.75 -4 90)
			(layer "B.Fab")
			(hide yes)
			(effects
				(font
					(size 0.7 0.7)
					(thickness 0.15)
				)
				(justify left bottom mirror)
			)
		)
		(fp_text user "License: Apache-2.0"
			(at -1.75 -6.5 90)
			(layer "B.Fab")
			(hide yes)
			(effects
				(font
					(size 0.7 0.7)
					(thickness 0.15)
				)
				(justify left bottom mirror)
			)
		)
		(fp_text user "Author: Antmicro"
			(at -1.829 -5.25 90)
			(layer "B.Fab")
			(hide yes)
			(effects
				(font
					(size 0.7 0.7)
					(thickness 0.15)
				)
				(justify left bottom mirror)
			)
		)
		(pad "1" smd roundrect
			(at -0.954 -1.1 270)
			(size 0.55 1)
			(layers "B.Cu" "B.Paste" "B.Mask")
			(roundrect_rratio 0.15)
			(net 688 "Net-(U38-CLK)")
			(pinfunction "CLK")
			(pintype "input")
		)
		(pad "2" smd roundrect
			(at -0.003 -1.1 270)
			(size 0.55 1)
			(layers "B.Cu" "B.Paste" "B.Mask")
			(roundrect_rratio 0.15)
			(net 1 "GND")
			(pinfunction "GND")
			(pintype "power_in")
		)
		(pad "3" smd roundrect
			(at 0.947 -1.1 270)
			(size 0.55 1)
			(layers "B.Cu" "B.Paste" "B.Mask")
			(roundrect_rratio 0.15)
			(net 117 "3V3_STDB")
			(pinfunction "D")
			(pintype "input")
		)
		(pad "4" smd roundrect
			(at 0.947 1.214 270)
			(size 0.55 1)
			(layers "B.Cu" "B.Paste" "B.Mask")
			(roundrect_rratio 0.15)
			(net 689 "Net-(U38-Q)")
			(pinfunction "Q")
			(pintype "output")
		)
		(pad "5" smd roundrect
			(at -0.003 1.214 270)
			(size 0.55 1)
			(layers "B.Cu" "B.Paste" "B.Mask")
			(roundrect_rratio 0.15)
			(net 117 "3V3_STDB")
			(pinfunction "VCC")
			(pintype "power_in")
		)
		(pad "6" smd roundrect
			(at -0.954 1.214 270)
			(size 0.55 1)
			(layers "B.Cu" "B.Paste" "B.Mask")
			(roundrect_rratio 0.15)
			(net 629 "Net-(D37-A)")
			(pinfunction "~{CLR}")
			(pintype "input")
		)
	)
)
